FILE_TYPE = MACRO_DRAWING;
SET COLOR_WIRE YELLOW;
SET COLOR_PROP ORANGE;
SET COLOR_DOT WHITE;
SET COLOR_ARC YELLOW;
SET COLOR_BODY GREEN;
SET COLOR_NOTE PURPLE;
SET PROP_DISPLAY VALUE;
SET PAGE_NUMBER P53;
FORCEADD OFFPAGE..1
(-7825 5850);
FORCEPROP 2 LAST $XR0 144 
J 0
(-8107 5850);
DISPLAY 0.638298 (-8107 5850);
PAINT MONO (-8107 5850);
FORCEPROP 2 LAST CDS_LIB standard
J 0
(-7825 5850);
DISPLAY INVISIBLE (-7825 5850);
FORCEPROP 1 LAST OFFPAGE TRUE
J 0
(-7500 5725);
DISPLAY 0.872340 (-7500 5725);
PAINT GREEN (-7500 5725);
DISPLAY INVISIBLE (-7500 5725);
FORCEPROP 1 LAST COMMENT_BODY TRUE
J 0
(-7700 5750);
DISPLAY 0.872340 (-7700 5750);
PAINT GREEN (-7700 5750);
DISPLAY INVISIBLE (-7700 5750);
FORCEPROP 2 LAST PATH I109
J 0
(-7775 5925);
DISPLAY 0.680851 (-7775 5925);
DISPLAY INVISIBLE (-7775 5925);
FORCEADD OFFPAGE..1
(-7825 5800);
FORCEPROP 2 LAST $XR0 144 
J 0
(-8107 5800);
DISPLAY 0.638298 (-8107 5800);
PAINT MONO (-8107 5800);
FORCEPROP 2 LAST CDS_LIB standard
J 0
(-7825 5800);
DISPLAY INVISIBLE (-7825 5800);
FORCEPROP 1 LAST OFFPAGE TRUE
J 0
(-7500 5675);
DISPLAY 0.872340 (-7500 5675);
PAINT GREEN (-7500 5675);
DISPLAY INVISIBLE (-7500 5675);
FORCEPROP 1 LAST COMMENT_BODY TRUE
J 0
(-7700 5700);
DISPLAY 0.872340 (-7700 5700);
PAINT GREEN (-7700 5700);
DISPLAY INVISIBLE (-7700 5700);
FORCEPROP 2 LAST PATH I110
J 0
(-7775 5875);
DISPLAY 0.680851 (-7775 5875);
DISPLAY INVISIBLE (-7775 5875);
FORCEADD OFFPAGE..4
R 2
(-7500 4725);
FORCEPROP 2 LAST $XR0 122 
J 0
(-7752 4725);
DISPLAY 0.638298 (-7752 4725);
PAINT MONO (-7752 4725);
FORCEPROP 2 LAST CDS_LIB standard
J 0
(-7500 4725);
DISPLAY INVISIBLE (-7500 4725);
FORCEPROP 1 LAST OFFPAGE TRUE
J 2
(-7825 4600);
DISPLAY 0.872340 (-7825 4600);
PAINT GREEN (-7825 4600);
DISPLAY INVISIBLE (-7825 4600);
FORCEPROP 1 LAST COMMENT_BODY TRUE
J 2
(-7475 4625);
DISPLAY 0.872340 (-7475 4625);
PAINT GREEN (-7475 4625);
DISPLAY INVISIBLE (-7475 4625);
FORCEPROP 2 LAST PATH I111
J 0
(-7450 4800);
DISPLAY 0.680851 (-7450 4800);
DISPLAY INVISIBLE (-7450 4800);
FORCEADD OFFPAGE..4
R 2
(-7500 4775);
FORCEPROP 2 LAST $XR0 122 
J 0
(-7752 4775);
DISPLAY 0.638298 (-7752 4775);
PAINT MONO (-7752 4775);
FORCEPROP 2 LAST CDS_LIB standard
J 0
(-7500 4775);
DISPLAY INVISIBLE (-7500 4775);
FORCEPROP 1 LAST OFFPAGE TRUE
J 2
(-7825 4650);
DISPLAY 0.872340 (-7825 4650);
PAINT GREEN (-7825 4650);
DISPLAY INVISIBLE (-7825 4650);
FORCEPROP 1 LAST COMMENT_BODY TRUE
J 2
(-7475 4675);
DISPLAY 0.872340 (-7475 4675);
PAINT GREEN (-7475 4675);
DISPLAY INVISIBLE (-7475 4675);
FORCEPROP 2 LAST PATH I112
J 0
(-7450 4850);
DISPLAY 0.680851 (-7450 4850);
DISPLAY INVISIBLE (-7450 4850);
FORCEADD OFFPAGE..4
R 2
(-7500 4825);
FORCEPROP 2 LAST $XR0 122 
J 0
(-7752 4825);
DISPLAY 0.638298 (-7752 4825);
PAINT MONO (-7752 4825);
FORCEPROP 2 LAST CDS_LIB standard
J 0
(-7500 4825);
DISPLAY INVISIBLE (-7500 4825);
FORCEPROP 1 LAST OFFPAGE TRUE
J 2
(-7825 4700);
DISPLAY 0.872340 (-7825 4700);
PAINT GREEN (-7825 4700);
DISPLAY INVISIBLE (-7825 4700);
FORCEPROP 1 LAST COMMENT_BODY TRUE
J 2
(-7475 4725);
DISPLAY 0.872340 (-7475 4725);
PAINT GREEN (-7475 4725);
DISPLAY INVISIBLE (-7475 4725);
FORCEPROP 2 LAST PATH I113
J 0
(-7450 4900);
DISPLAY 0.680851 (-7450 4900);
DISPLAY INVISIBLE (-7450 4900);
FORCEADD OFFPAGE..4
R 2
(-7500 4875);
FORCEPROP 2 LAST $XR0 122 
J 0
(-7752 4875);
DISPLAY 0.638298 (-7752 4875);
PAINT MONO (-7752 4875);
FORCEPROP 2 LAST CDS_LIB standard
J 0
(-7500 4875);
DISPLAY INVISIBLE (-7500 4875);
FORCEPROP 1 LAST OFFPAGE TRUE
J 2
(-7825 4750);
DISPLAY 0.872340 (-7825 4750);
PAINT GREEN (-7825 4750);
DISPLAY INVISIBLE (-7825 4750);
FORCEPROP 1 LAST COMMENT_BODY TRUE
J 2
(-7475 4775);
DISPLAY 0.872340 (-7475 4775);
PAINT GREEN (-7475 4775);
DISPLAY INVISIBLE (-7475 4775);
FORCEPROP 2 LAST PATH I114
J 0
(-7450 4950);
DISPLAY 0.680851 (-7450 4950);
DISPLAY INVISIBLE (-7450 4950);
FORCEADD OFFPAGE..4
R 2
(-7275 5025);
FORCEPROP 2 LAST $XR0 26 
J 0
(-7496 5025);
DISPLAY 0.638298 (-7496 5025);
PAINT MONO (-7496 5025);
FORCEPROP 2 LAST CDS_LIB standard
J 0
(-7275 5025);
DISPLAY INVISIBLE (-7275 5025);
FORCEPROP 1 LAST OFFPAGE TRUE
J 2
(-7600 4900);
DISPLAY 0.872340 (-7600 4900);
PAINT GREEN (-7600 4900);
DISPLAY INVISIBLE (-7600 4900);
FORCEPROP 1 LAST COMMENT_BODY TRUE
J 2
(-7250 4925);
DISPLAY 0.872340 (-7250 4925);
PAINT GREEN (-7250 4925);
DISPLAY INVISIBLE (-7250 4925);
FORCEPROP 2 LAST PATH I115
J 0
(-7525 5075);
DISPLAY 0.680851 (-7525 5075);
DISPLAY INVISIBLE (-7525 5075);
FORCEADD OFFPAGE..4
R 2
(-7275 5075);
FORCEPROP 2 LAST $XR0 26 
J 0
(-7496 5075);
DISPLAY 0.638298 (-7496 5075);
PAINT MONO (-7496 5075);
FORCEPROP 2 LAST CDS_LIB standard
J 0
(-7275 5075);
DISPLAY INVISIBLE (-7275 5075);
FORCEPROP 1 LAST OFFPAGE TRUE
J 2
(-7600 4950);
DISPLAY 0.872340 (-7600 4950);
PAINT GREEN (-7600 4950);
DISPLAY INVISIBLE (-7600 4950);
FORCEPROP 1 LAST COMMENT_BODY TRUE
J 2
(-7250 4975);
DISPLAY 0.872340 (-7250 4975);
PAINT GREEN (-7250 4975);
DISPLAY INVISIBLE (-7250 4975);
FORCEPROP 2 LAST PATH I116
J 0
(-7525 5125);
DISPLAY 0.680851 (-7525 5125);
DISPLAY INVISIBLE (-7525 5125);
FORCEADD TAP..6
(-6800 5275);
FORCEPROP 3 LASTPIN (-6750 5275) SIG_NAME P3E_CPU1_P4_RX_DN<3>
J 0
(-6740 5285);
DISPLAY 0.659574 (-6740 5285);
PAINT MONO (-6740 5285);
DISPLAY INVISIBLE (-6740 5285);
FORCEPROP 1 LASTPIN (-6750 5275) BN 3
J 0
(-6802 5283);
DISPLAY 0.680851 (-6802 5283);
PAINT MONO (-6802 5283);
FORCEPROP 2 LAST CDS_LIB standard
J 0
(-6800 5275);
DISPLAY INVISIBLE (-6800 5275);
FORCEPROP 1 LAST BODY_TYPE PLUMBING
J 0
(-6800 5225);
DISPLAY 0.574468 (-6800 5225);
PAINT GREEN (-6800 5225);
DISPLAY INVISIBLE (-6800 5225);
FORCEPROP 1 LAST HDL_TAP TRUE
J 0
(-6475 5150);
DISPLAY 0.574468 (-6475 5150);
PAINT GREEN (-6475 5150);
DISPLAY INVISIBLE (-6475 5150);
FORCEPROP 1 LAST PATH I117
J 0
(-6802 5275);
DISPLAY 0.872340 (-6802 5275);
PAINT GREEN (-6802 5275);
DISPLAY INVISIBLE (-6802 5275);
FORCEADD TAP..6
(-6800 5375);
FORCEPROP 3 LASTPIN (-6750 5375) SIG_NAME P3E_CPU1_P4_RX_DN<2>
J 0
(-6740 5385);
DISPLAY 0.659574 (-6740 5385);
PAINT MONO (-6740 5385);
DISPLAY INVISIBLE (-6740 5385);
FORCEPROP 1 LASTPIN (-6750 5375) BN 2
J 0
(-6802 5383);
DISPLAY 0.680851 (-6802 5383);
PAINT MONO (-6802 5383);
FORCEPROP 2 LAST CDS_LIB standard
J 0
(-6800 5375);
DISPLAY INVISIBLE (-6800 5375);
FORCEPROP 1 LAST BODY_TYPE PLUMBING
J 0
(-6800 5325);
DISPLAY 0.574468 (-6800 5325);
PAINT GREEN (-6800 5325);
DISPLAY INVISIBLE (-6800 5325);
FORCEPROP 1 LAST HDL_TAP TRUE
J 0
(-6475 5250);
DISPLAY 0.574468 (-6475 5250);
PAINT GREEN (-6475 5250);
DISPLAY INVISIBLE (-6475 5250);
FORCEPROP 1 LAST PATH I118
J 0
(-6802 5375);
DISPLAY 0.872340 (-6802 5375);
PAINT GREEN (-6802 5375);
DISPLAY INVISIBLE (-6802 5375);
FORCEADD TAP..6
(-6800 5475);
FORCEPROP 3 LASTPIN (-6750 5475) SIG_NAME P3E_CPU1_P4_RX_DN<1>
J 0
(-6740 5485);
DISPLAY 0.659574 (-6740 5485);
PAINT MONO (-6740 5485);
DISPLAY INVISIBLE (-6740 5485);
FORCEPROP 1 LASTPIN (-6750 5475) BN 1
J 0
(-6802 5483);
DISPLAY 0.680851 (-6802 5483);
PAINT MONO (-6802 5483);
FORCEPROP 2 LAST CDS_LIB standard
J 0
(-6800 5475);
DISPLAY INVISIBLE (-6800 5475);
FORCEPROP 1 LAST BODY_TYPE PLUMBING
J 0
(-6800 5425);
DISPLAY 0.574468 (-6800 5425);
PAINT GREEN (-6800 5425);
DISPLAY INVISIBLE (-6800 5425);
FORCEPROP 1 LAST HDL_TAP TRUE
J 0
(-6475 5350);
DISPLAY 0.574468 (-6475 5350);
PAINT GREEN (-6475 5350);
DISPLAY INVISIBLE (-6475 5350);
FORCEPROP 1 LAST PATH I119
J 0
(-6802 5475);
DISPLAY 0.872340 (-6802 5475);
PAINT GREEN (-6802 5475);
DISPLAY INVISIBLE (-6802 5475);
FORCEADD TAP..6
(-6650 5325);
FORCEPROP 3 LASTPIN (-6600 5325) SIG_NAME P3E_CPU1_P4_RX_DP<3>
J 0
(-6590 5335);
DISPLAY 0.659574 (-6590 5335);
PAINT MONO (-6590 5335);
DISPLAY INVISIBLE (-6590 5335);
FORCEPROP 1 LASTPIN (-6600 5325) BN 3
J 0
(-6652 5333);
DISPLAY 0.680851 (-6652 5333);
PAINT MONO (-6652 5333);
FORCEPROP 2 LAST CDS_LIB standard
J 0
(-6650 5325);
DISPLAY INVISIBLE (-6650 5325);
FORCEPROP 1 LAST BODY_TYPE PLUMBING
J 0
(-6650 5275);
DISPLAY 0.574468 (-6650 5275);
PAINT GREEN (-6650 5275);
DISPLAY INVISIBLE (-6650 5275);
FORCEPROP 1 LAST HDL_TAP TRUE
J 0
(-6325 5200);
DISPLAY 0.574468 (-6325 5200);
PAINT GREEN (-6325 5200);
DISPLAY INVISIBLE (-6325 5200);
FORCEPROP 1 LAST PATH I120
J 0
(-6652 5325);
DISPLAY 0.872340 (-6652 5325);
PAINT GREEN (-6652 5325);
DISPLAY INVISIBLE (-6652 5325);
FORCEADD TAP..6
(-6650 5425);
FORCEPROP 3 LASTPIN (-6600 5425) SIG_NAME P3E_CPU1_P4_RX_DP<2>
J 0
(-6590 5435);
DISPLAY 0.659574 (-6590 5435);
PAINT MONO (-6590 5435);
DISPLAY INVISIBLE (-6590 5435);
FORCEPROP 1 LASTPIN (-6600 5425) BN 2
J 0
(-6652 5433);
DISPLAY 0.680851 (-6652 5433);
PAINT MONO (-6652 5433);
FORCEPROP 2 LAST CDS_LIB standard
J 0
(-6650 5425);
DISPLAY INVISIBLE (-6650 5425);
FORCEPROP 1 LAST BODY_TYPE PLUMBING
J 0
(-6650 5375);
DISPLAY 0.574468 (-6650 5375);
PAINT GREEN (-6650 5375);
DISPLAY INVISIBLE (-6650 5375);
FORCEPROP 1 LAST HDL_TAP TRUE
J 0
(-6325 5300);
DISPLAY 0.574468 (-6325 5300);
PAINT GREEN (-6325 5300);
DISPLAY INVISIBLE (-6325 5300);
FORCEPROP 1 LAST PATH I121
J 0
(-6652 5425);
DISPLAY 0.872340 (-6652 5425);
PAINT GREEN (-6652 5425);
DISPLAY INVISIBLE (-6652 5425);
FORCEADD TAP..6
(-6650 5525);
FORCEPROP 3 LASTPIN (-6600 5525) SIG_NAME P3E_CPU1_P4_RX_DP<1>
J 0
(-6590 5535);
DISPLAY 0.659574 (-6590 5535);
PAINT MONO (-6590 5535);
DISPLAY INVISIBLE (-6590 5535);
FORCEPROP 1 LASTPIN (-6600 5525) BN 1
J 0
(-6652 5533);
DISPLAY 0.680851 (-6652 5533);
PAINT MONO (-6652 5533);
FORCEPROP 2 LAST CDS_LIB standard
J 0
(-6650 5525);
DISPLAY INVISIBLE (-6650 5525);
FORCEPROP 1 LAST BODY_TYPE PLUMBING
J 0
(-6650 5475);
DISPLAY 0.574468 (-6650 5475);
PAINT GREEN (-6650 5475);
DISPLAY INVISIBLE (-6650 5475);
FORCEPROP 1 LAST HDL_TAP TRUE
J 0
(-6325 5400);
DISPLAY 0.574468 (-6325 5400);
PAINT GREEN (-6325 5400);
DISPLAY INVISIBLE (-6325 5400);
FORCEPROP 1 LAST PATH I122
J 0
(-6652 5525);
DISPLAY 0.872340 (-6652 5525);
PAINT GREEN (-6652 5525);
DISPLAY INVISIBLE (-6652 5525);
FORCEADD TAP..6
(-6800 5575);
FORCEPROP 3 LASTPIN (-6750 5575) SIG_NAME P3E_CPU1_P4_RX_DN<0>
J 0
(-6740 5585);
DISPLAY 0.659574 (-6740 5585);
PAINT MONO (-6740 5585);
DISPLAY INVISIBLE (-6740 5585);
FORCEPROP 1 LASTPIN (-6750 5575) BN 0
J 0
(-6802 5583);
DISPLAY 0.680851 (-6802 5583);
PAINT MONO (-6802 5583);
FORCEPROP 2 LAST CDS_LIB standard
J 0
(-6800 5575);
DISPLAY INVISIBLE (-6800 5575);
FORCEPROP 1 LAST BODY_TYPE PLUMBING
J 0
(-6800 5525);
DISPLAY 0.574468 (-6800 5525);
PAINT GREEN (-6800 5525);
DISPLAY INVISIBLE (-6800 5525);
FORCEPROP 1 LAST HDL_TAP TRUE
J 0
(-6475 5450);
DISPLAY 0.574468 (-6475 5450);
PAINT GREEN (-6475 5450);
DISPLAY INVISIBLE (-6475 5450);
FORCEPROP 1 LAST PATH I123
J 0
(-6802 5575);
DISPLAY 0.872340 (-6802 5575);
PAINT GREEN (-6802 5575);
DISPLAY INVISIBLE (-6802 5575);
FORCEADD TAP..6
(-6650 5625);
FORCEPROP 3 LASTPIN (-6600 5625) SIG_NAME P3E_CPU1_P4_RX_DP<0>
J 0
(-6590 5635);
DISPLAY 0.659574 (-6590 5635);
PAINT MONO (-6590 5635);
DISPLAY INVISIBLE (-6590 5635);
FORCEPROP 1 LASTPIN (-6600 5625) BN 0
J 0
(-6652 5633);
DISPLAY 0.680851 (-6652 5633);
PAINT MONO (-6652 5633);
FORCEPROP 2 LAST CDS_LIB standard
J 0
(-6650 5625);
DISPLAY INVISIBLE (-6650 5625);
FORCEPROP 1 LAST BODY_TYPE PLUMBING
J 0
(-6650 5575);
DISPLAY 0.574468 (-6650 5575);
PAINT GREEN (-6650 5575);
DISPLAY INVISIBLE (-6650 5575);
FORCEPROP 1 LAST HDL_TAP TRUE
J 0
(-6325 5500);
DISPLAY 0.574468 (-6325 5500);
PAINT GREEN (-6325 5500);
DISPLAY INVISIBLE (-6325 5500);
FORCEPROP 1 LAST PATH I124
J 0
(-6652 5625);
DISPLAY 0.872340 (-6652 5625);
PAINT GREEN (-6652 5625);
DISPLAY INVISIBLE (-6652 5625);
FORCEADD TAP..6
R 2
(-3800 5425);
FORCEPROP 3 LASTPIN (-3850 5425) SIG_NAME P3E_CPU1_P4_TX_DP<2>
J 0
(-3840 5435);
DISPLAY 0.659574 (-3840 5435);
PAINT MONO (-3840 5435);
DISPLAY INVISIBLE (-3840 5435);
FORCEPROP 1 LASTPIN (-3850 5425) BN 2
J 2
(-3798 5433);
DISPLAY 0.680851 (-3798 5433);
PAINT MONO (-3798 5433);
FORCEPROP 2 LAST ROOM RISER1
J 0
(-4300 5475);
DISPLAY 0.829787 (-4300 5475);
PAINT RED (-4300 5475);
DISPLAY INVISIBLE (-4300 5475);
FORCEPROP 2 LAST BOM_COST IO_SLOT
J 0
(-4300 5525);
DISPLAY 0.829787 (-4300 5525);
DISPLAY INVISIBLE (-4300 5525);
FORCEPROP 2 LAST CDS_LIB standard
J 0
(-3800 5425);
DISPLAY INVISIBLE (-3800 5425);
FORCEPROP 1 LAST BODY_TYPE PLUMBING
J 2
(-3800 5375);
DISPLAY 0.702128 (-3800 5375);
PAINT GREEN (-3800 5375);
DISPLAY INVISIBLE (-3800 5375);
FORCEPROP 1 LAST HDL_TAP TRUE
J 2
(-4125 5300);
DISPLAY 0.702128 (-4125 5300);
PAINT GREEN (-4125 5300);
DISPLAY INVISIBLE (-4125 5300);
FORCEPROP 1 LAST PATH I125
J 2
(-3798 5425);
DISPLAY 0.872340 (-3798 5425);
PAINT GREEN (-3798 5425);
DISPLAY INVISIBLE (-3798 5425);
FORCEADD TAP..6
R 2
(-3800 5325);
FORCEPROP 3 LASTPIN (-3850 5325) SIG_NAME P3E_CPU1_P4_TX_DP<3>
J 0
(-3840 5335);
DISPLAY 0.659574 (-3840 5335);
PAINT MONO (-3840 5335);
DISPLAY INVISIBLE (-3840 5335);
FORCEPROP 1 LASTPIN (-3850 5325) BN 3
J 2
(-3798 5333);
DISPLAY 0.680851 (-3798 5333);
PAINT MONO (-3798 5333);
FORCEPROP 2 LAST ROOM RISER1
J 0
(-4300 5375);
DISPLAY 0.829787 (-4300 5375);
PAINT RED (-4300 5375);
DISPLAY INVISIBLE (-4300 5375);
FORCEPROP 2 LAST BOM_COST IO_SLOT
J 0
(-4300 5425);
DISPLAY 0.829787 (-4300 5425);
DISPLAY INVISIBLE (-4300 5425);
FORCEPROP 2 LAST CDS_LIB standard
J 0
(-3800 5325);
DISPLAY INVISIBLE (-3800 5325);
FORCEPROP 1 LAST BODY_TYPE PLUMBING
J 2
(-3800 5275);
DISPLAY 0.702128 (-3800 5275);
PAINT GREEN (-3800 5275);
DISPLAY INVISIBLE (-3800 5275);
FORCEPROP 1 LAST HDL_TAP TRUE
J 2
(-4125 5200);
DISPLAY 0.702128 (-4125 5200);
PAINT GREEN (-4125 5200);
DISPLAY INVISIBLE (-4125 5200);
FORCEPROP 1 LAST PATH I126
J 2
(-3798 5325);
DISPLAY 0.872340 (-3798 5325);
PAINT GREEN (-3798 5325);
DISPLAY INVISIBLE (-3798 5325);
FORCEADD TAP..6
R 2
(-3800 5525);
FORCEPROP 3 LASTPIN (-3850 5525) SIG_NAME P3E_CPU1_P4_TX_DP<1>
J 0
(-3840 5535);
DISPLAY 0.659574 (-3840 5535);
PAINT MONO (-3840 5535);
DISPLAY INVISIBLE (-3840 5535);
FORCEPROP 1 LASTPIN (-3850 5525) BN 1
J 2
(-3798 5533);
DISPLAY 0.680851 (-3798 5533);
PAINT MONO (-3798 5533);
FORCEPROP 2 LAST ROOM RISER1
J 0
(-4300 5575);
DISPLAY 0.829787 (-4300 5575);
PAINT RED (-4300 5575);
DISPLAY INVISIBLE (-4300 5575);
FORCEPROP 2 LAST BOM_COST IO_SLOT
J 0
(-4300 5625);
DISPLAY 0.829787 (-4300 5625);
DISPLAY INVISIBLE (-4300 5625);
FORCEPROP 2 LAST CDS_LIB standard
J 0
(-3800 5525);
DISPLAY INVISIBLE (-3800 5525);
FORCEPROP 1 LAST BODY_TYPE PLUMBING
J 2
(-3800 5475);
DISPLAY 0.702128 (-3800 5475);
PAINT GREEN (-3800 5475);
DISPLAY INVISIBLE (-3800 5475);
FORCEPROP 1 LAST HDL_TAP TRUE
J 2
(-4125 5400);
DISPLAY 0.702128 (-4125 5400);
PAINT GREEN (-4125 5400);
DISPLAY INVISIBLE (-4125 5400);
FORCEPROP 1 LAST PATH I127
J 2
(-3798 5525);
DISPLAY 0.872340 (-3798 5525);
PAINT GREEN (-3798 5525);
DISPLAY INVISIBLE (-3798 5525);
FORCEADD TAP..6
R 2
(-3800 5625);
FORCEPROP 3 LASTPIN (-3850 5625) SIG_NAME P3E_CPU1_P4_TX_DP<0>
J 0
(-3840 5635);
DISPLAY 0.659574 (-3840 5635);
PAINT MONO (-3840 5635);
DISPLAY INVISIBLE (-3840 5635);
FORCEPROP 1 LASTPIN (-3850 5625) BN 0
J 2
(-3798 5633);
DISPLAY 0.680851 (-3798 5633);
PAINT MONO (-3798 5633);
FORCEPROP 2 LAST ROOM RISER1
J 0
(-4300 5675);
DISPLAY 0.829787 (-4300 5675);
PAINT RED (-4300 5675);
DISPLAY INVISIBLE (-4300 5675);
FORCEPROP 2 LAST BOM_COST IO_SLOT
J 0
(-4300 5725);
DISPLAY 0.829787 (-4300 5725);
DISPLAY INVISIBLE (-4300 5725);
FORCEPROP 2 LAST CDS_LIB standard
J 0
(-3800 5625);
DISPLAY INVISIBLE (-3800 5625);
FORCEPROP 1 LAST BODY_TYPE PLUMBING
J 2
(-3800 5575);
DISPLAY 0.702128 (-3800 5575);
PAINT GREEN (-3800 5575);
DISPLAY INVISIBLE (-3800 5575);
FORCEPROP 1 LAST HDL_TAP TRUE
J 2
(-4125 5500);
DISPLAY 0.702128 (-4125 5500);
PAINT GREEN (-4125 5500);
DISPLAY INVISIBLE (-4125 5500);
FORCEPROP 1 LAST PATH I128
J 2
(-3798 5625);
DISPLAY 0.872340 (-3798 5625);
PAINT GREEN (-3798 5625);
DISPLAY INVISIBLE (-3798 5625);
FORCEADD TAP..6
R 2
(-3650 5275);
FORCEPROP 3 LASTPIN (-3700 5275) SIG_NAME P3E_CPU1_P4_TX_DN<3>
J 0
(-3690 5285);
DISPLAY 0.659574 (-3690 5285);
PAINT MONO (-3690 5285);
DISPLAY INVISIBLE (-3690 5285);
FORCEPROP 1 LASTPIN (-3700 5275) BN 3
J 2
(-3648 5283);
DISPLAY 0.680851 (-3648 5283);
PAINT MONO (-3648 5283);
FORCEPROP 2 LAST ROOM RISER1
J 0
(-4150 5325);
DISPLAY 0.829787 (-4150 5325);
PAINT RED (-4150 5325);
DISPLAY INVISIBLE (-4150 5325);
FORCEPROP 2 LAST BOM_COST IO_SLOT
J 0
(-4150 5375);
DISPLAY 0.829787 (-4150 5375);
DISPLAY INVISIBLE (-4150 5375);
FORCEPROP 2 LAST CDS_LIB standard
J 0
(-3650 5275);
DISPLAY INVISIBLE (-3650 5275);
FORCEPROP 1 LAST BODY_TYPE PLUMBING
J 2
(-3650 5225);
DISPLAY 0.702128 (-3650 5225);
PAINT GREEN (-3650 5225);
DISPLAY INVISIBLE (-3650 5225);
FORCEPROP 1 LAST HDL_TAP TRUE
J 2
(-3975 5150);
DISPLAY 0.702128 (-3975 5150);
PAINT GREEN (-3975 5150);
DISPLAY INVISIBLE (-3975 5150);
FORCEPROP 1 LAST PATH I129
J 2
(-3648 5275);
DISPLAY 0.872340 (-3648 5275);
PAINT GREEN (-3648 5275);
DISPLAY INVISIBLE (-3648 5275);
FORCEADD TAP..6
R 2
(-3650 5475);
FORCEPROP 3 LASTPIN (-3700 5475) SIG_NAME P3E_CPU1_P4_TX_DN<1>
J 0
(-3690 5485);
DISPLAY 0.659574 (-3690 5485);
PAINT MONO (-3690 5485);
DISPLAY INVISIBLE (-3690 5485);
FORCEPROP 1 LASTPIN (-3700 5475) BN 1
J 2
(-3648 5483);
DISPLAY 0.680851 (-3648 5483);
PAINT MONO (-3648 5483);
FORCEPROP 2 LAST ROOM RISER1
J 0
(-4150 5525);
DISPLAY 0.829787 (-4150 5525);
PAINT RED (-4150 5525);
DISPLAY INVISIBLE (-4150 5525);
FORCEPROP 2 LAST BOM_COST IO_SLOT
J 0
(-4150 5575);
DISPLAY 0.829787 (-4150 5575);
DISPLAY INVISIBLE (-4150 5575);
FORCEPROP 2 LAST CDS_LIB standard
J 0
(-3650 5475);
DISPLAY INVISIBLE (-3650 5475);
FORCEPROP 1 LAST BODY_TYPE PLUMBING
J 2
(-3650 5425);
DISPLAY 0.702128 (-3650 5425);
PAINT GREEN (-3650 5425);
DISPLAY INVISIBLE (-3650 5425);
FORCEPROP 1 LAST HDL_TAP TRUE
J 2
(-3975 5350);
DISPLAY 0.702128 (-3975 5350);
PAINT GREEN (-3975 5350);
DISPLAY INVISIBLE (-3975 5350);
FORCEPROP 1 LAST PATH I130
J 2
(-3648 5475);
DISPLAY 0.872340 (-3648 5475);
PAINT GREEN (-3648 5475);
DISPLAY INVISIBLE (-3648 5475);
FORCEADD TAP..6
R 2
(-3650 5375);
FORCEPROP 3 LASTPIN (-3700 5375) SIG_NAME P3E_CPU1_P4_TX_DN<2>
J 0
(-3690 5385);
DISPLAY 0.659574 (-3690 5385);
PAINT MONO (-3690 5385);
DISPLAY INVISIBLE (-3690 5385);
FORCEPROP 1 LASTPIN (-3700 5375) BN 2
J 2
(-3648 5383);
DISPLAY 0.680851 (-3648 5383);
PAINT MONO (-3648 5383);
FORCEPROP 2 LAST ROOM RISER1
J 0
(-4150 5425);
DISPLAY 0.829787 (-4150 5425);
PAINT RED (-4150 5425);
DISPLAY INVISIBLE (-4150 5425);
FORCEPROP 2 LAST BOM_COST IO_SLOT
J 0
(-4150 5475);
DISPLAY 0.829787 (-4150 5475);
DISPLAY INVISIBLE (-4150 5475);
FORCEPROP 2 LAST CDS_LIB standard
J 0
(-3650 5375);
DISPLAY INVISIBLE (-3650 5375);
FORCEPROP 1 LAST BODY_TYPE PLUMBING
J 2
(-3650 5325);
DISPLAY 0.702128 (-3650 5325);
PAINT GREEN (-3650 5325);
DISPLAY INVISIBLE (-3650 5325);
FORCEPROP 1 LAST HDL_TAP TRUE
J 2
(-3975 5250);
DISPLAY 0.702128 (-3975 5250);
PAINT GREEN (-3975 5250);
DISPLAY INVISIBLE (-3975 5250);
FORCEPROP 1 LAST PATH I131
J 2
(-3648 5375);
DISPLAY 0.872340 (-3648 5375);
PAINT GREEN (-3648 5375);
DISPLAY INVISIBLE (-3648 5375);
FORCEADD Q_CAP_DIFFBUS..2
R 2
(-3050 4775);
FORCEPROP 1 LAST LOCATION C2073
J 2
(-3125 4775);
DISPLAY 0.723404 (-3125 4775);
PAINT GREEN (-3125 4775);
FORCEPROP 0 LAST $SEC 1
J 0
(-2550 4825);
DISPLAY 0.680851 (-2550 4825);
PAINT MONO (-2550 4825);
DISPLAY INVISIBLE (-2550 4825);
FORCEPROP 0 LAST CDS_SEC 1
J 0
(-2550 4825);
DISPLAY 0.680851 (-2550 4825);
DISPLAY INVISIBLE (-2550 4825);
FORCEPROP 0 LASTPIN (-2975 4775) $PN 1
J 0
(-2965 4785);
DISPLAY 0.680851 (-2965 4785);
PAINT MONO (-2965 4785);
FORCEPROP 0 LASTPIN (-3125 4775) $PN 2
J 2
(-3135 4785);
DISPLAY 0.680851 (-3135 4785);
PAINT MONO (-3135 4785);
FORCEPROP 2 LAST VALUE DIFF BUS_0.22UF
J 2
(-2550 4775);
DISPLAY 0.553191 (-2550 4775);
FORCEPROP 2 LAST CDS_LIB pure_quanta
J 0
(-3050 4775);
DISPLAY INVISIBLE (-3050 4775);
FORCEPROP 1 LAST CDS_LMAN_SYM_OUTLINE -25,50,25,-50
J 2
(-3050 4775);
DISPLAY 0.468085 (-3050 4775);
PAINT GREEN (-3050 4775);
DISPLAY INVISIBLE (-3050 4775);
FORCEPROP 0 LAST VOLTAGE 6.3V
J 2
(-2850 4600);
DISPLAY 0.553191 (-2850 4600);
PAINT GREEN (-2850 4600);
DISPLAY INVISIBLE (-2850 4600);
FORCEPROP 0 LAST TOLERANCE 20%
J 2
(-2975 4600);
DISPLAY 0.553191 (-2975 4600);
PAINT GREEN (-2975 4600);
DISPLAY INVISIBLE (-2975 4600);
FORCEPROP 0 LAST PACK_TYPE C0201
J 2
(-3075 4600);
DISPLAY 0.553191 (-3075 4600);
PAINT GREEN (-3075 4600);
DISPLAY INVISIBLE (-3075 4600);
FORCEPROP 1 LAST MATERIAL X6S
J 2
(-3116 4654);
DISPLAY 0.574468 (-3116 4654);
PAINT GREEN (-3116 4654);
DISPLAY INVISIBLE (-3116 4654);
FORCEPROP 1 LAST PIN_NAMES_ROTATE TRUE
J 2
(-3050 4775);
DISPLAY 0.489362 (-3050 4775);
PAINT GREEN (-3050 4775);
DISPLAY INVISIBLE (-3050 4775);
FORCEPROP 1 LAST PATH I132
J 2
(-3050 4775);
DISPLAY 0.723404 (-3050 4775);
DISPLAY INVISIBLE (-3050 4775);
FORCEPROP 1 LAST PART_NUMBER SP_CH4221MEE01
J 2
(-2841 4538);
DISPLAY 0.574468 (-2841 4538);
PAINT GREEN (-2841 4538);
DISPLAY INVISIBLE (-2841 4538);
FORCEADD Q_CAP_DIFFBUS..2
R 2
(-3050 4725);
FORCEPROP 1 LAST LOCATION C2074
J 2
(-3125 4725);
DISPLAY 0.723404 (-3125 4725);
PAINT GREEN (-3125 4725);
FORCEPROP 0 LAST $SEC 1
J 0
(-2550 4775);
DISPLAY 0.680851 (-2550 4775);
PAINT MONO (-2550 4775);
DISPLAY INVISIBLE (-2550 4775);
FORCEPROP 0 LAST CDS_SEC 1
J 0
(-2550 4775);
DISPLAY 0.680851 (-2550 4775);
DISPLAY INVISIBLE (-2550 4775);
FORCEPROP 0 LASTPIN (-2975 4725) $PN 1
J 0
(-2965 4735);
DISPLAY 0.680851 (-2965 4735);
PAINT MONO (-2965 4735);
FORCEPROP 0 LASTPIN (-3125 4725) $PN 2
J 2
(-3135 4735);
DISPLAY 0.680851 (-3135 4735);
PAINT MONO (-3135 4735);
FORCEPROP 2 LAST VOLTAGE 6.3V
J 2
(-2859 4612);
DISPLAY 0.553191 (-2859 4612);
PAINT GREEN (-2859 4612);
FORCEPROP 2 LAST TOLERANCE 20%
J 2
(-2984 4612);
DISPLAY 0.553191 (-2984 4612);
PAINT GREEN (-2984 4612);
FORCEPROP 2 LAST VALUE DIFF BUS_0.22UF
J 2
(-2550 4725);
DISPLAY 0.553191 (-2550 4725);
FORCEPROP 1 LAST MATERIAL X6S
J 2
(-3125 4666);
DISPLAY 0.574468 (-3125 4666);
PAINT GREEN (-3125 4666);
FORCEPROP 2 LAST PACK_TYPE C0201
J 2
(-3084 4612);
DISPLAY 0.553191 (-3084 4612);
PAINT GREEN (-3084 4612);
FORCEPROP 2 LAST CDS_LIB pure_quanta
J 0
(-3050 4725);
DISPLAY INVISIBLE (-3050 4725);
FORCEPROP 1 LAST CDS_LMAN_SYM_OUTLINE -25,50,25,-50
J 2
(-3050 4725);
DISPLAY 0.468085 (-3050 4725);
PAINT GREEN (-3050 4725);
DISPLAY INVISIBLE (-3050 4725);
FORCEPROP 1 LAST PIN_NAMES_ROTATE TRUE
J 2
(-3050 4725);
DISPLAY 0.489362 (-3050 4725);
PAINT GREEN (-3050 4725);
DISPLAY INVISIBLE (-3050 4725);
FORCEPROP 1 LAST PATH I133
J 2
(-3050 4725);
DISPLAY 0.723404 (-3050 4725);
DISPLAY INVISIBLE (-3050 4725);
FORCEPROP 1 LAST PART_NUMBER SP_CH4221MEE01
J 2
(-2850 4550);
DISPLAY 0.574468 (-2850 4550);
PAINT GREEN (-2850 4550);
DISPLAY INVISIBLE (-2850 4550);
FORCEADD Q_CAP_DIFFBUS..2
R 2
(-3050 4825);
FORCEPROP 1 LAST LOCATION C2076
J 2
(-3125 4825);
DISPLAY 0.723404 (-3125 4825);
PAINT GREEN (-3125 4825);
FORCEPROP 0 LAST $SEC 1
J 0
(-2550 4875);
DISPLAY 0.680851 (-2550 4875);
PAINT MONO (-2550 4875);
DISPLAY INVISIBLE (-2550 4875);
FORCEPROP 0 LAST CDS_SEC 1
J 0
(-2550 4875);
DISPLAY 0.680851 (-2550 4875);
DISPLAY INVISIBLE (-2550 4875);
FORCEPROP 0 LASTPIN (-2975 4825) $PN 1
J 0
(-2965 4835);
DISPLAY 0.680851 (-2965 4835);
PAINT MONO (-2965 4835);
FORCEPROP 0 LASTPIN (-3125 4825) $PN 2
J 2
(-3135 4835);
DISPLAY 0.680851 (-3135 4835);
PAINT MONO (-3135 4835);
FORCEPROP 2 LAST VALUE DIFF BUS_0.22UF
J 2
(-2550 4825);
DISPLAY 0.553191 (-2550 4825);
FORCEPROP 2 LAST CDS_LIB pure_quanta
J 0
(-3050 4825);
DISPLAY INVISIBLE (-3050 4825);
FORCEPROP 1 LAST CDS_LMAN_SYM_OUTLINE -25,50,25,-50
J 2
(-3050 4825);
DISPLAY 0.468085 (-3050 4825);
PAINT GREEN (-3050 4825);
DISPLAY INVISIBLE (-3050 4825);
FORCEPROP 1 LAST PIN_NAMES_ROTATE TRUE
J 2
(-3050 4825);
DISPLAY 0.489362 (-3050 4825);
PAINT GREEN (-3050 4825);
DISPLAY INVISIBLE (-3050 4825);
FORCEPROP 1 LAST MATERIAL X6S
J 2
(-3116 4704);
DISPLAY 0.574468 (-3116 4704);
PAINT GREEN (-3116 4704);
DISPLAY INVISIBLE (-3116 4704);
FORCEPROP 0 LAST PACK_TYPE C0201
J 2
(-3075 4650);
DISPLAY 0.553191 (-3075 4650);
PAINT GREEN (-3075 4650);
DISPLAY INVISIBLE (-3075 4650);
FORCEPROP 0 LAST TOLERANCE 20%
J 2
(-2975 4650);
DISPLAY 0.553191 (-2975 4650);
PAINT GREEN (-2975 4650);
DISPLAY INVISIBLE (-2975 4650);
FORCEPROP 0 LAST VOLTAGE 6.3V
J 2
(-2850 4650);
DISPLAY 0.553191 (-2850 4650);
PAINT GREEN (-2850 4650);
DISPLAY INVISIBLE (-2850 4650);
FORCEPROP 1 LAST PATH I134
J 2
(-3050 4825);
DISPLAY 0.723404 (-3050 4825);
DISPLAY INVISIBLE (-3050 4825);
FORCEPROP 1 LAST PART_NUMBER SP_CH4221MEE01
J 2
(-2841 4588);
DISPLAY 0.574468 (-2841 4588);
PAINT GREEN (-2841 4588);
DISPLAY INVISIBLE (-2841 4588);
FORCEADD Q_CAP_DIFFBUS..2
R 2
(-3050 4875);
FORCEPROP 1 LAST LOCATION C2075
J 2
(-3125 4875);
DISPLAY 0.723404 (-3125 4875);
PAINT GREEN (-3125 4875);
FORCEPROP 0 LAST $SEC 1
J 0
(-2550 4925);
DISPLAY 0.680851 (-2550 4925);
PAINT MONO (-2550 4925);
DISPLAY INVISIBLE (-2550 4925);
FORCEPROP 0 LAST CDS_SEC 1
J 0
(-2550 4925);
DISPLAY 0.680851 (-2550 4925);
DISPLAY INVISIBLE (-2550 4925);
FORCEPROP 0 LASTPIN (-2975 4875) $PN 1
J 0
(-2965 4885);
DISPLAY 0.680851 (-2965 4885);
PAINT MONO (-2965 4885);
FORCEPROP 0 LASTPIN (-3125 4875) $PN 2
J 2
(-3135 4885);
DISPLAY 0.680851 (-3135 4885);
PAINT MONO (-3135 4885);
FORCEPROP 2 LAST VALUE DIFF BUS_0.22UF
J 2
(-2550 4875);
DISPLAY 0.553191 (-2550 4875);
FORCEPROP 2 LAST CDS_LIB pure_quanta
J 0
(-3050 4875);
DISPLAY INVISIBLE (-3050 4875);
FORCEPROP 1 LAST CDS_LMAN_SYM_OUTLINE -25,50,25,-50
J 2
(-3050 4875);
DISPLAY 0.468085 (-3050 4875);
PAINT GREEN (-3050 4875);
DISPLAY INVISIBLE (-3050 4875);
FORCEPROP 0 LAST VOLTAGE 6.3V
J 2
(-2850 4700);
DISPLAY 0.553191 (-2850 4700);
PAINT GREEN (-2850 4700);
DISPLAY INVISIBLE (-2850 4700);
FORCEPROP 0 LAST TOLERANCE 20%
J 2
(-2975 4700);
DISPLAY 0.553191 (-2975 4700);
PAINT GREEN (-2975 4700);
DISPLAY INVISIBLE (-2975 4700);
FORCEPROP 0 LAST PACK_TYPE C0201
J 2
(-3075 4700);
DISPLAY 0.553191 (-3075 4700);
PAINT GREEN (-3075 4700);
DISPLAY INVISIBLE (-3075 4700);
FORCEPROP 1 LAST MATERIAL X6S
J 2
(-3116 4754);
DISPLAY 0.574468 (-3116 4754);
PAINT GREEN (-3116 4754);
DISPLAY INVISIBLE (-3116 4754);
FORCEPROP 1 LAST PIN_NAMES_ROTATE TRUE
J 2
(-3050 4875);
DISPLAY 0.489362 (-3050 4875);
PAINT GREEN (-3050 4875);
DISPLAY INVISIBLE (-3050 4875);
FORCEPROP 1 LAST PATH I135
J 2
(-3050 4875);
DISPLAY 0.723404 (-3050 4875);
DISPLAY INVISIBLE (-3050 4875);
FORCEPROP 1 LAST PART_NUMBER SP_CH4221MEE01
J 2
(-2841 4638);
DISPLAY 0.574468 (-2841 4638);
PAINT GREEN (-2841 4638);
DISPLAY INVISIBLE (-2841 4638);
FORCEADD OFFPAGE..2
(-3075 5025);
FORCEPROP 2 LAST $XR0 26 
J 0
(-2886 5025);
DISPLAY 0.638298 (-2886 5025);
PAINT MONO (-2886 5025);
FORCEPROP 2 LAST CDS_LIB standard
J 0
(-3075 5025);
DISPLAY INVISIBLE (-3075 5025);
FORCEPROP 1 LAST OFFPAGE TRUE
J 0
(-2750 4900);
DISPLAY 0.872340 (-2750 4900);
PAINT GREEN (-2750 4900);
DISPLAY INVISIBLE (-2750 4900);
FORCEPROP 1 LAST COMMENT_BODY TRUE
J 0
(-3120 4930);
DISPLAY 0.872340 (-3120 4930);
PAINT GREEN (-3120 4930);
DISPLAY INVISIBLE (-3120 4930);
FORCEPROP 2 LAST PATH I136
J 0
(-2875 5075);
DISPLAY 0.680851 (-2875 5075);
DISPLAY INVISIBLE (-2875 5075);
FORCEADD OFFPAGE..2
(-3075 5075);
FORCEPROP 2 LAST $XR0 26 
J 0
(-2886 5075);
DISPLAY 0.638298 (-2886 5075);
PAINT MONO (-2886 5075);
FORCEPROP 2 LAST CDS_LIB standard
J 0
(-3075 5075);
DISPLAY INVISIBLE (-3075 5075);
FORCEPROP 1 LAST OFFPAGE TRUE
J 0
(-2750 4950);
DISPLAY 0.872340 (-2750 4950);
PAINT GREEN (-2750 4950);
DISPLAY INVISIBLE (-2750 4950);
FORCEPROP 1 LAST COMMENT_BODY TRUE
J 0
(-3120 4980);
DISPLAY 0.872340 (-3120 4980);
PAINT GREEN (-3120 4980);
DISPLAY INVISIBLE (-3120 4980);
FORCEPROP 2 LAST PATH I137
J 0
(-2875 5125);
DISPLAY 0.680851 (-2875 5125);
DISPLAY INVISIBLE (-2875 5125);
FORCEADD TAP..6
R 2
(-3650 5575);
FORCEPROP 3 LASTPIN (-3700 5575) SIG_NAME P3E_CPU1_P4_TX_DN<0>
J 0
(-3690 5585);
DISPLAY 0.659574 (-3690 5585);
PAINT MONO (-3690 5585);
DISPLAY INVISIBLE (-3690 5585);
FORCEPROP 1 LASTPIN (-3700 5575) BN 0
J 2
(-3648 5583);
DISPLAY 0.680851 (-3648 5583);
PAINT MONO (-3648 5583);
FORCEPROP 2 LAST ROOM RISER1
J 0
(-4150 5625);
DISPLAY 0.829787 (-4150 5625);
PAINT RED (-4150 5625);
DISPLAY INVISIBLE (-4150 5625);
FORCEPROP 2 LAST BOM_COST IO_SLOT
J 0
(-4150 5675);
DISPLAY 0.829787 (-4150 5675);
DISPLAY INVISIBLE (-4150 5675);
FORCEPROP 2 LAST CDS_LIB standard
J 0
(-3650 5575);
DISPLAY INVISIBLE (-3650 5575);
FORCEPROP 1 LAST BODY_TYPE PLUMBING
J 2
(-3650 5525);
DISPLAY 0.702128 (-3650 5525);
PAINT GREEN (-3650 5525);
DISPLAY INVISIBLE (-3650 5525);
FORCEPROP 1 LAST HDL_TAP TRUE
J 2
(-3975 5450);
DISPLAY 0.702128 (-3975 5450);
PAINT GREEN (-3975 5450);
DISPLAY INVISIBLE (-3975 5450);
FORCEPROP 1 LAST PATH I138
J 2
(-3648 5575);
DISPLAY 0.872340 (-3648 5575);
PAINT GREEN (-3648 5575);
DISPLAY INVISIBLE (-3648 5575);
FORCEADD OFFPAGE..2
(-2700 5800);
FORCEPROP 2 LAST $XR0 67 
J 0
(-2511 5800);
DISPLAY 0.638298 (-2511 5800);
PAINT MONO (-2511 5800);
FORCEPROP 2 LAST CDS_LIB standard
J 0
(-2700 5800);
DISPLAY INVISIBLE (-2700 5800);
FORCEPROP 1 LAST OFFPAGE TRUE
J 0
(-2375 5675);
DISPLAY 0.872340 (-2375 5675);
PAINT GREEN (-2375 5675);
DISPLAY INVISIBLE (-2375 5675);
FORCEPROP 1 LAST COMMENT_BODY TRUE
J 0
(-2745 5705);
DISPLAY 0.872340 (-2745 5705);
PAINT GREEN (-2745 5705);
DISPLAY INVISIBLE (-2745 5705);
FORCEPROP 2 LAST PATH I139
J 0
(-2525 5875);
DISPLAY 0.680851 (-2525 5875);
DISPLAY INVISIBLE (-2525 5875);
FORCEADD OFFPAGE..2
(-2700 5850);
FORCEPROP 2 LAST $XR0 67 
J 0
(-2511 5850);
DISPLAY 0.638298 (-2511 5850);
PAINT MONO (-2511 5850);
FORCEPROP 2 LAST CDS_LIB standard
J 0
(-2700 5850);
DISPLAY INVISIBLE (-2700 5850);
FORCEPROP 1 LAST OFFPAGE TRUE
J 0
(-2375 5725);
DISPLAY 0.872340 (-2375 5725);
PAINT GREEN (-2375 5725);
DISPLAY INVISIBLE (-2375 5725);
FORCEPROP 1 LAST COMMENT_BODY TRUE
J 0
(-2745 5755);
DISPLAY 0.872340 (-2745 5755);
PAINT GREEN (-2745 5755);
DISPLAY INVISIBLE (-2745 5755);
FORCEPROP 2 LAST PATH I140
J 0
(-2525 5925);
DISPLAY 0.680851 (-2525 5925);
DISPLAY INVISIBLE (-2525 5925);
FORCEADD OFFPAGE..2
(-1575 4775);
FORCEPROP 2 LAST $XR0 122 
J 0
(-1386 4775);
DISPLAY 0.638298 (-1386 4775);
PAINT MONO (-1386 4775);
FORCEPROP 2 LAST CDS_LIB standard
J 0
(-1575 4775);
DISPLAY INVISIBLE (-1575 4775);
FORCEPROP 1 LAST OFFPAGE TRUE
J 0
(-1250 4650);
DISPLAY 0.872340 (-1250 4650);
PAINT GREEN (-1250 4650);
DISPLAY INVISIBLE (-1250 4650);
FORCEPROP 1 LAST COMMENT_BODY TRUE
J 0
(-1620 4680);
DISPLAY 0.872340 (-1620 4680);
PAINT GREEN (-1620 4680);
DISPLAY INVISIBLE (-1620 4680);
FORCEPROP 2 LAST PATH I141
J 0
(-1400 4850);
DISPLAY 0.680851 (-1400 4850);
DISPLAY INVISIBLE (-1400 4850);
FORCEADD OFFPAGE..2
(-1575 4725);
FORCEPROP 2 LAST $XR0 122 
J 0
(-1386 4725);
DISPLAY 0.638298 (-1386 4725);
PAINT MONO (-1386 4725);
FORCEPROP 2 LAST CDS_LIB standard
J 0
(-1575 4725);
DISPLAY INVISIBLE (-1575 4725);
FORCEPROP 1 LAST OFFPAGE TRUE
J 0
(-1250 4600);
DISPLAY 0.872340 (-1250 4600);
PAINT GREEN (-1250 4600);
DISPLAY INVISIBLE (-1250 4600);
FORCEPROP 1 LAST COMMENT_BODY TRUE
J 0
(-1620 4630);
DISPLAY 0.872340 (-1620 4630);
PAINT GREEN (-1620 4630);
DISPLAY INVISIBLE (-1620 4630);
FORCEPROP 2 LAST PATH I142
J 0
(-1400 4800);
DISPLAY 0.680851 (-1400 4800);
DISPLAY INVISIBLE (-1400 4800);
FORCEADD OFFPAGE..2
(-1575 4825);
FORCEPROP 2 LAST $XR0 122 
J 0
(-1386 4825);
DISPLAY 0.638298 (-1386 4825);
PAINT MONO (-1386 4825);
FORCEPROP 2 LAST CDS_LIB standard
J 0
(-1575 4825);
DISPLAY INVISIBLE (-1575 4825);
FORCEPROP 1 LAST OFFPAGE TRUE
J 0
(-1250 4700);
DISPLAY 0.872340 (-1250 4700);
PAINT GREEN (-1250 4700);
DISPLAY INVISIBLE (-1250 4700);
FORCEPROP 1 LAST COMMENT_BODY TRUE
J 0
(-1620 4730);
DISPLAY 0.872340 (-1620 4730);
PAINT GREEN (-1620 4730);
DISPLAY INVISIBLE (-1620 4730);
FORCEPROP 2 LAST PATH I143
J 0
(-1400 4900);
DISPLAY 0.680851 (-1400 4900);
DISPLAY INVISIBLE (-1400 4900);
FORCEADD OFFPAGE..2
(-1575 4875);
FORCEPROP 2 LAST $XR0 122 
J 0
(-1386 4875);
DISPLAY 0.638298 (-1386 4875);
PAINT MONO (-1386 4875);
FORCEPROP 2 LAST CDS_LIB standard
J 0
(-1575 4875);
DISPLAY INVISIBLE (-1575 4875);
FORCEPROP 1 LAST OFFPAGE TRUE
J 0
(-1250 4750);
DISPLAY 0.872340 (-1250 4750);
PAINT GREEN (-1250 4750);
DISPLAY INVISIBLE (-1250 4750);
FORCEPROP 1 LAST COMMENT_BODY TRUE
J 0
(-1620 4780);
DISPLAY 0.872340 (-1620 4780);
PAINT GREEN (-1620 4780);
DISPLAY INVISIBLE (-1620 4780);
FORCEPROP 2 LAST PATH I144
J 0
(-1400 4950);
DISPLAY 0.680851 (-1400 4950);
DISPLAY INVISIBLE (-1400 4950);
FORCEADD GENOA_SP5..19
(-5175 5225);
FORCEPROP 1 LAST LOCATION U26
J 0
(-5970 6051);
DISPLAY 0.489362 (-5970 6051);
PAINT SKYBLUE (-5970 6051);
FORCEPROP 0 LAST $SEC 19
J 0
(-5950 6100);
DISPLAY 0.680851 (-5950 6100);
PAINT MONO (-5950 6100);
DISPLAY INVISIBLE (-5950 6100);
FORCEPROP 0 LAST CDS_SEC 19
J 0
(-5975 6100);
DISPLAY 1.021277 (-5975 6100);
DISPLAY INVISIBLE (-5975 6100);
FORCEPROP 0 LASTPIN (-6125 5575) $PN DG53
J 2
(-6135 5585);
DISPLAY 0.489362 (-6135 5585);
PAINT MONO (-6135 5585);
FORCEPROP 0 LASTPIN (-6125 5475) $PN DG50
J 2
(-6135 5485);
DISPLAY 0.489362 (-6135 5485);
PAINT MONO (-6135 5485);
FORCEPROP 0 LASTPIN (-6125 5375) $PN DG47
J 2
(-6135 5385);
DISPLAY 0.489362 (-6135 5385);
PAINT MONO (-6135 5385);
FORCEPROP 0 LASTPIN (-6125 5275) $PN DG44
J 2
(-6135 5285);
DISPLAY 0.489362 (-6135 5285);
PAINT MONO (-6135 5285);
FORCEPROP 0 LASTPIN (-6125 5625) $PN DG54
J 2
(-6135 5635);
DISPLAY 0.489362 (-6135 5635);
PAINT MONO (-6135 5635);
FORCEPROP 0 LASTPIN (-6125 5525) $PN DG51
J 2
(-6135 5535);
DISPLAY 0.489362 (-6135 5535);
PAINT MONO (-6135 5535);
FORCEPROP 0 LASTPIN (-6125 5425) $PN DG48
J 2
(-6135 5435);
DISPLAY 0.489362 (-6135 5435);
PAINT MONO (-6135 5435);
FORCEPROP 0 LASTPIN (-6125 5325) $PN DG45
J 2
(-6135 5335);
DISPLAY 0.489362 (-6135 5335);
PAINT MONO (-6135 5335);
FORCEPROP 0 LASTPIN (-4225 5575) $PN DE52
J 0
(-4215 5585);
DISPLAY 0.489362 (-4215 5585);
PAINT MONO (-4215 5585);
FORCEPROP 0 LASTPIN (-4225 5475) $PN DE49
J 0
(-4215 5485);
DISPLAY 0.489362 (-4215 5485);
PAINT MONO (-4215 5485);
FORCEPROP 0 LASTPIN (-4225 5375) $PN DE46
J 0
(-4215 5385);
DISPLAY 0.489362 (-4215 5385);
PAINT MONO (-4215 5385);
FORCEPROP 0 LASTPIN (-4225 5275) $PN DE43
J 0
(-4215 5285);
DISPLAY 0.489362 (-4215 5285);
PAINT MONO (-4215 5285);
FORCEPROP 0 LASTPIN (-4225 5625) $PN DE53
J 0
(-4215 5635);
DISPLAY 0.489362 (-4215 5635);
PAINT MONO (-4215 5635);
FORCEPROP 0 LASTPIN (-4225 5525) $PN DE50
J 0
(-4215 5535);
DISPLAY 0.489362 (-4215 5535);
PAINT MONO (-4215 5535);
FORCEPROP 0 LASTPIN (-4225 5425) $PN DE47
J 0
(-4215 5435);
DISPLAY 0.489362 (-4215 5435);
PAINT MONO (-4215 5435);
FORCEPROP 0 LASTPIN (-4225 5325) $PN DE44
J 0
(-4215 5335);
DISPLAY 0.489362 (-4215 5335);
PAINT MONO (-4215 5335);
FORCEPROP 0 LASTPIN (-6125 4825) $PN E44
J 2
(-6135 4835);
DISPLAY 0.489362 (-6135 4835);
PAINT MONO (-6135 4835);
FORCEPROP 0 LASTPIN (-6125 4725) $PN E41
J 2
(-6135 4735);
DISPLAY 0.489362 (-6135 4735);
PAINT MONO (-6135 4735);
FORCEPROP 0 LASTPIN (-6125 4875) $PN E43
J 2
(-6135 4885);
DISPLAY 0.489362 (-6135 4885);
PAINT MONO (-6135 4885);
FORCEPROP 0 LASTPIN (-6125 4775) $PN E40
J 2
(-6135 4785);
DISPLAY 0.489362 (-6135 4785);
PAINT MONO (-6135 4785);
FORCEPROP 0 LASTPIN (-4225 4825) $PN C45
J 0
(-4215 4835);
DISPLAY 0.489362 (-4215 4835);
PAINT MONO (-4215 4835);
FORCEPROP 0 LASTPIN (-4225 4725) $PN C42
J 0
(-4215 4735);
DISPLAY 0.489362 (-4215 4735);
PAINT MONO (-4215 4735);
FORCEPROP 0 LASTPIN (-4225 4875) $PN C44
J 0
(-4215 4885);
DISPLAY 0.489362 (-4215 4885);
PAINT MONO (-4215 4885);
FORCEPROP 0 LASTPIN (-4225 4775) $PN C41
J 0
(-4215 4785);
DISPLAY 0.489362 (-4215 4785);
PAINT MONO (-4215 4785);
FORCEPROP 0 LASTPIN (-6125 5125) $PN E50
J 2
(-6135 5135);
DISPLAY 0.489362 (-6135 5135);
PAINT MONO (-6135 5135);
FORCEPROP 0 LASTPIN (-6125 5025) $PN E47
J 2
(-6135 5035);
DISPLAY 0.489362 (-6135 5035);
PAINT MONO (-6135 5035);
FORCEPROP 0 LASTPIN (-6125 5175) $PN E49
J 2
(-6135 5185);
DISPLAY 0.489362 (-6135 5185);
PAINT MONO (-6135 5185);
FORCEPROP 0 LASTPIN (-6125 5075) $PN E46
J 2
(-6135 5085);
DISPLAY 0.489362 (-6135 5085);
PAINT MONO (-6135 5085);
FORCEPROP 0 LASTPIN (-4225 5125) $PN C51
J 0
(-4215 5135);
DISPLAY 0.489362 (-4215 5135);
PAINT MONO (-4215 5135);
FORCEPROP 0 LASTPIN (-4225 5025) $PN C48
J 0
(-4215 5035);
DISPLAY 0.489362 (-4215 5035);
PAINT MONO (-4215 5035);
FORCEPROP 0 LASTPIN (-4225 5175) $PN C50
J 0
(-4215 5185);
DISPLAY 0.489362 (-4215 5185);
PAINT MONO (-4215 5185);
FORCEPROP 0 LASTPIN (-4225 5075) $PN C47
J 0
(-4215 5085);
DISPLAY 0.489362 (-4215 5085);
PAINT MONO (-4215 5085);
FORCEPROP 1 LAST MATERIAL IO
J 0
(-5970 5857);
DISPLAY 0.489362 (-5970 5857);
PAINT SKYBLUE (-5970 5857);
FORCEPROP 2 LAST VALUE SOCKET6096_13568-001
J 0
(-5975 5900);
DISPLAY 0.489362 (-5975 5900);
PAINT SKYBLUE (-5975 5900);
FORCEPROP 2 LAST PART_TYPE SMLF
J 0
(-5975 6000);
DISPLAY 1.021277 (-5975 6000);
FORCEPROP 2 LAST CDS_LIB pure_quanta
J 0
(-5175 5225);
DISPLAY INVISIBLE (-5175 5225);
FORCEPROP 1 LAST CDS_LMAN_SYM_OUTLINE -800,600,800,-600
J 0
(-5175 5225);
DISPLAY 0.468085 (-5175 5225);
PAINT GREEN (-5175 5225);
DISPLAY INVISIBLE (-5175 5225);
FORCEPROP 1 LAST NEEDS_NO_SIZE TRUE
J 0
(-5175 5225);
DISPLAY 0.723404 (-5175 5225);
PAINT GREEN (-5175 5225);
DISPLAY INVISIBLE (-5175 5225);
FORCEPROP 1 LAST PATH I145
J 0
(-5175 5225);
DISPLAY 0.723404 (-5175 5225);
PAINT GREEN (-5175 5225);
DISPLAY INVISIBLE (-5175 5225);
FORCEPROP 1 LAST PART_NUMBER DGA^6000030
J 0
(-5975 5950);
DISPLAY 0.489362 (-5975 5950);
PAINT SKYBLUE (-5975 5950);
DISPLAY INVISIBLE (-5975 5950);
FORCEADD QUANTA_TITLE_BLOCK_C..1
(0 0);
FORCEPROP 0 LAST CDS_CON_LAST_MODIFIED Thu Sep 14 16:12:37 2023
J 0
(-1885 15);
DISPLAY INVISIBLE (-1885 15);
FORCEPROP 1 LAST CUSTOM_TXT_CDS <CON_LAST_MODIFIED>
J 0
(-1885 15);
DISPLAY 0.978723 (-1885 15);
FORCEPROP 2 LAST CUSTOM_TXT_CDS <XR_PAGE_TITLE>
J 0
(-7890 5250);
DISPLAY 0.638298 (-7890 5250);
PAINT PINK (-7890 5250);
DISPLAY INVISIBLE (-7890 5250);
FORCEPROP 1 LAST CUSTOM_TXT_CDS <NAME_2>
J 0
(-3175 50);
FORCEPROP 1 LAST CUSTOM_TXT_CDS <NAME_1>
J 0
(-3175 175);
FORCEPROP 1 LAST CUSTOM_TXT_CDS <Q_NUMBER>
J 0
(-1403 103);
DISPLAY 1.212766 (-1403 103);
FORCEPROP 1 LAST CUSTOM_TXT_CDS <Q_PROJ>
J 0
(-2382 102);
DISPLAY 1.212766 (-2382 102);
FORCEPROP 1 LAST CUSTOM_TXT_CDS <Q_REV>
J 0
(-184 103);
DISPLAY 1.212766 (-184 103);
FORCEPROP 1 LAST CUSTOM_TXT_CDS <CON_PAGE_NUM> OF <CON_TOTAL_PAGES>
J 0
(-446 18);
DISPLAY 0.978723 (-446 18);
FORCEPROP 1 LAST Q_TITLE CPU1 PCIE P4/P5/WAFL
J 0
(-9366 26);
DISPLAY 2.446809 (-9366 26);
PAINT GREEN (-9366 26);
FORCEPROP 2 LAST PAGE_BORDER TRUE
J 0
(-7890 5250);
DISPLAY 0.638298 (-7890 5250);
PAINT PINK (-7890 5250);
DISPLAY INVISIBLE (-7890 5250);
FORCEPROP 2 LAST CDS_LIB pure_quanta
J 0
(0 0);
DISPLAY INVISIBLE (0 0);
FORCEPROP 1 LAST CDS_LMAN_SYM_OUTLINE -9475,6775,100,-125
J 0
(0 0);
DISPLAY 0.468085 (0 0);
PAINT GREEN (0 0);
DISPLAY INVISIBLE (0 0);
FORCEPROP 2 LAST CDS_XR_PAGE_TITLE CR-53 : @T6G_MB_LIB.T6G(SCH_1):PAGE53
J 0
(-7890 5250);
DISPLAY 0.638298 (-7890 5250);
PAINT PINK (-7890 5250);
DISPLAY INVISIBLE (-7890 5250);
FORCEPROP 1 LAST Q_DEPT BU9
J 1
(-3763 49);
DISPLAY 1.957447 (-3763 49);
PAINT GREEN (-3763 49);
DISPLAY INVISIBLE (-3763 49);
FORCEPROP 1 LAST COMMENT_BODY TRUE
J 0
(12 -13);
DISPLAY 0.978723 (12 -13);
PAINT GREEN (12 -13);
DISPLAY INVISIBLE (12 -13);
WIRE 17 -1 (-6850 5300)(-6850 5400);
WIRE 17 -1 (-6850 5400)(-6850 5500);
WIRE 17 -1 (-6850 5500)(-6850 5600);
WIRE 17 -1 (-6850 5600)(-6850 5800);
WIRE 17 -1 (-6850 5800)(-7775 5800);
FORCEPROP 2 LAST SIG_NAME P3E_CPU1_P4_RX_DN<3:0>
J 0
(-7610 5810);
DISPLAY 0.489362 (-7610 5810);
WIRE 17 -1 (-6700 5350)(-6700 5450);
WIRE 17 -1 (-6700 5450)(-6700 5550);
WIRE 17 -1 (-6700 5550)(-6700 5650);
WIRE 17 -1 (-6700 5650)(-6700 5850);
WIRE 17 -1 (-6700 5850)(-7775 5850);
FORCEPROP 2 LAST SIG_NAME P3E_CPU1_P4_RX_DP<3:0>
J 0
(-7585 5885);
DISPLAY 0.489362 (-7585 5885);
WIRE 17 -1 (-3600 5500)(-3600 5400);
WIRE 17 -1 (-3600 5600)(-3600 5500);
WIRE 17 -1 (-3600 5400)(-3600 5300);
WIRE 17 -1 (-3600 5800)(-3600 5600);
WIRE 17 -1 (-3600 5800)(-2750 5800);
FORCEPROP 2 LAST SIG_NAME P3E_CPU1_P4_TX_DN<3:0>
J 0
(-3410 5810);
DISPLAY 0.489362 (-3410 5810);
WIRE 17 -1 (-3750 5550)(-3750 5450);
WIRE 17 -1 (-3750 5650)(-3750 5550);
WIRE 17 -1 (-3750 5450)(-3750 5350);
WIRE 17 -1 (-3750 5850)(-3750 5650);
WIRE 17 -1 (-3750 5850)(-2750 5850);
FORCEPROP 2 LAST SIG_NAME P3E_CPU1_P4_TX_DP<3:0>
J 0
(-3410 5885);
DISPLAY 0.489362 (-3410 5885);
WIRE 16 -1 (-4225 4825)(-3125 4825);
FORCEPROP 2 LAST SIG_NAME P3E_CPU1_P5_TX_DN<0>
J 0
(-3885 4835);
DISPLAY 0.489362 (-3885 4835);
FORCEPROP 2 LASTPROP $XRERR UNIQUE?
J 0
(-4125 4835);
DISPLAY 0.638298 (-4125 4835);
PAINT MONO (-4125 4835);
DISPLAY INVISIBLE (-4125 4835);
WIRE 16 -1 (-4225 4875)(-3125 4875);
FORCEPROP 2 LAST SIG_NAME P3E_CPU1_P5_TX_DP<0>
J 0
(-3885 4885);
DISPLAY 0.489362 (-3885 4885);
FORCEPROP 2 LASTPROP $XRERR UNIQUE?
J 0
(-4125 4885);
DISPLAY 0.638298 (-4125 4885);
PAINT MONO (-4125 4885);
DISPLAY INVISIBLE (-4125 4885);
WIRE 16 -1 (-4225 4725)(-3125 4725);
FORCEPROP 2 LAST SIG_NAME P3E_CPU1_P5_TX_DN<1>
J 0
(-3885 4735);
DISPLAY 0.489362 (-3885 4735);
FORCEPROP 2 LASTPROP $XRERR UNIQUE?
J 0
(-4125 4735);
DISPLAY 0.638298 (-4125 4735);
PAINT MONO (-4125 4735);
DISPLAY INVISIBLE (-4125 4735);
WIRE 16 -1 (-4225 4775)(-3125 4775);
FORCEPROP 2 LAST SIG_NAME P3E_CPU1_P5_TX_DP<1>
J 0
(-3885 4785);
DISPLAY 0.489362 (-3885 4785);
FORCEPROP 2 LASTPROP $XRERR UNIQUE?
J 0
(-4125 4785);
DISPLAY 0.638298 (-4125 4785);
PAINT MONO (-4125 4785);
DISPLAY INVISIBLE (-4125 4785);
WIRE 16 -1 (-7450 4725)(-6125 4725);
FORCEPROP 2 LAST SIG_NAME P3E_CPU1_P5_RX_DP<1>
J 0
(-7210 4735);
DISPLAY 0.489362 (-7210 4735);
WIRE 16 -1 (-6125 4875)(-7450 4875);
FORCEPROP 2 LAST SIG_NAME P3E_CPU1_P5_RX_DN<0>
J 0
(-7210 4885);
DISPLAY 0.489362 (-7210 4885);
WIRE 16 -1 (-7450 4775)(-6125 4775);
FORCEPROP 2 LAST SIG_NAME P3E_CPU1_P5_RX_DN<1>
J 0
(-7210 4785);
DISPLAY 0.489362 (-7210 4785);
WIRE 16 -1 (-7450 4825)(-6125 4825);
FORCEPROP 2 LAST SIG_NAME P3E_CPU1_P5_RX_DP<0>
J 0
(-7210 4835);
DISPLAY 0.489362 (-7210 4835);
WIRE 16 -1 (-7225 5025)(-6125 5025);
FORCEPROP 2 LAST SIG_NAME WAFL_CPU0_TX0_CPU1_RX1_DN
J 0
(-7085 5035);
DISPLAY 0.489362 (-7085 5035);
FORCEPROP 0 LAST $PHYS_NET_NAME P3E_M2_0_SATA_RX_DP
J 0
(-7035 5064);
DISPLAY INVISIBLE (-7035 5064);
WIRE 16 -1 (-7225 5075)(-6125 5075);
FORCEPROP 2 LAST SIG_NAME WAFL_CPU0_TX0_CPU1_RX1_DP
J 0
(-7085 5085);
DISPLAY 0.489362 (-7085 5085);
WIRE 16 -1 (-4225 5025)(-3125 5025);
FORCEPROP 2 LAST SIG_NAME WAFL_CPU1_TX1_CPU0_RX0_DN
J 0
(-3925 5035);
DISPLAY 0.489362 (-3925 5035);
FORCEPROP 0 LAST $PHYS_NET_NAME P3E_M2_0_SATA_RX_DP
J 0
(-4035 5064);
DISPLAY INVISIBLE (-4035 5064);
WIRE 16 -1 (-2975 4875)(-1625 4875);
FORCEPROP 2 LAST SIG_NAME P3E_CPU1_P5_TX_C_DP<0>
J 0
(-2335 4885);
DISPLAY 0.489362 (-2335 4885);
WIRE 16 -1 (-2975 4825)(-1625 4825);
FORCEPROP 2 LAST SIG_NAME P3E_CPU1_P5_TX_C_DN<0>
J 0
(-2335 4835);
DISPLAY 0.489362 (-2335 4835);
WIRE 16 -1 (-2975 4775)(-1625 4775);
FORCEPROP 2 LAST SIG_NAME P3E_CPU1_P5_TX_C_DP<1>
J 0
(-2335 4785);
DISPLAY 0.489362 (-2335 4785);
WIRE 16 -1 (-2975 4725)(-1625 4725);
FORCEPROP 2 LAST SIG_NAME P3E_CPU1_P5_TX_C_DN<1>
J 0
(-2335 4735);
DISPLAY 0.489362 (-2335 4735);
WIRE 16 -1 (-4225 5325)(-3850 5325);
WIRE 16 -1 (-4225 5275)(-3700 5275);
WIRE 16 -1 (-4225 5075)(-3125 5075);
FORCEPROP 2 LAST SIG_NAME WAFL_CPU1_TX1_CPU0_RX0_DP
J 0
(-3925 5085);
DISPLAY 0.489362 (-3925 5085);
WIRE 16 -1 (-4225 5575)(-3700 5575);
WIRE 16 -1 (-4225 5475)(-3700 5475);
WIRE 16 -1 (-4225 5625)(-3850 5625);
WIRE 16 -1 (-4225 5525)(-3850 5525);
WIRE 16 -1 (-4225 5425)(-3850 5425);
WIRE 16 -1 (-4225 5375)(-3700 5375);
WIRE 16 -1 (-6600 5625)(-6125 5625);
WIRE 16 -1 (-6600 5425)(-6125 5425);
WIRE 16 -1 (-6600 5525)(-6125 5525);
WIRE 16 -1 (-6750 5575)(-6125 5575);
WIRE 16 -1 (-6750 5475)(-6125 5475);
WIRE 16 -1 (-6600 5325)(-6125 5325);
WIRE 16 -1 (-6750 5375)(-6125 5375);
WIRE 16 -1 (-6750 5275)(-6125 5275);
CIRCLE (-7275 4800)(-7130 4800);
PAINT YELLOW (-7275 4800);
FORCENOTE
CPU1 P4[3:0] TO M.2
(-2900 5500) 0;
DISPLAY LEFT (-2900 5500);
DISPLAY 2.000000 (-2900 5500);
FORCENOTE
P3E_CPU1_P5_RX_DP/N<0> PN SWAP
(-7950 4550) 0;
DISPLAY LEFT (-7950 4550);
DISPLAY 1.021277 (-7950 4550);
FORCENOTE
P3E_CPU1_P5_RX_DP/N<1> PN SWAP
(-7950 4450) 0;
DISPLAY LEFT (-7950 4450);
DISPLAY 1.021277 (-7950 4450);
FORCENOTE
CPU1 P5[3:2] TO EXAMAX
(-4050 4400) 0;
DISPLAY LEFT (-4050 4400);
DISPLAY 2.000000 (-4050 4400);
QUIT
